# BASEBOARD_FAB2 (Tioga Pass) — schematic netlist excerpt (pin names and nets, part order shuffled) for the footprints in the layout excerpt that follows; sources: Cadence DE-HDL packaged netlist, KiCad conversion of Wiwynn_Tioga_Pass_MB.brd

J1F3  CONN8_H62179001  CONN  pkg PIP  page 181
  IO1  = P3V3_STBY
  IO2  = FM_MP_PS_REDUNDANT_LOST_N
  IO3  = FM_MP_PS_FAIL_N
  IO4  = FM_MATED_IN_N
  IO5  = IRQ_SML1_PMBUS_ALERT_R_N
  IO6  = SMB_BMC_PMBUS_STBY_LVC3_SDA
  IO7  = SMB_BMC_PMBUS_STBY_LVC3_SCL
  IO8  = GND

R1G15  RES  1.00K 1% CHIP  pkg 0402  page 100 : A = PVDDQ_GHJ ; B = M_J_VREF

(kicad_pcb
	(version 20260206)
	(generator "pcbnew")
	(generator_version "10.0")
	(general
		(thickness 1.6)
		(legacy_teardrops no)
	)
	(paper "A4")
	(title_block
		(title "Wiwynn_Tioga_Pass_MB.brd")
		(comment 1 "Tioga Pass / footprints 976-977 of 4770")
	)
	(layers
		(0 "F.Cu" signal "TOP")
		(4 "In1.Cu" signal "L2GND")
		(6 "In2.Cu" signal "L3")
		(8 "In3.Cu" signal "L4GND")
		(10 "In4.Cu" signal "L5")
		(12 "In5.Cu" signal "L6GND")
		(14 "In6.Cu" signal "L7VCC")
		(16 "In7.Cu" signal "L8VCC")
		(18 "In8.Cu" signal "L9GND")
		(20 "In9.Cu" signal "L10")
		(22 "In10.Cu" signal "L11GND")
		(24 "In11.Cu" signal "L12")
		(26 "In12.Cu" signal "L13GND")
		(2 "B.Cu" signal "BOTTOM")
		(9 "F.Adhes" user "F.Adhesive")
		(11 "B.Adhes" user "B.Adhesive")
		(13 "F.Paste" user "Package Geometry/Pastemask Top")
		(15 "B.Paste" user "Package Geometry/Pastemask Bottom")
		(5 "F.SilkS" user "Ref Des/Silkscreen Top")
		(7 "B.SilkS" user "Ref Des/Silkscreen Bottom")
		(1 "F.Mask" user "Board Geometry/Soldermask Top")
		(3 "B.Mask" user "Board Geometry/Soldermask Bottom")
		(17 "Dwgs.User" user "User.Drawings")
		(19 "Cmts.User" user "User.Comments")
		(21 "Eco1.User" user "User.Eco1")
		(23 "Eco2.User" user "User.Eco2")
		(25 "Edge.Cuts" user "Board Geometry/Outline")
		(27 "Margin" user)
		(31 "F.CrtYd" user "Package Geometry/Place Bound Top")
		(29 "B.CrtYd" user "Package Geometry/Place Bound Bottom")
		(35 "F.Fab" user "Ref Des/Assembly Top")
		(33 "B.Fab" user "Ref Des/Assembly Bottom")
	)
	(footprint ""
		(layer "F.Cu")
		(at 18.4912 -26.67 90)
		(property "Reference" "J1F3"
			(at 1.91643 14.8463 0)
			(unlocked yes)
			(layer "B.SilkS")
			(effects
				(font
					(size 0.7874 0.5842)
					(thickness 0.1524)
				)
				(justify left mirror)
			)
		)
		(property "Value" ""
			(at 0 0 90)
			(layer "F.Fab")
			(effects
				(font
					(size 1.27 1.27)
				)
			)
		)
		(duplicate_pad_numbers_are_jumpers no)
		(fp_line
			(start 2.169922 -1.599946)
			(end 2.169922 10.349992)
			(stroke
				(width 0.1524)
				(type default)
			)
			(layer "F.SilkS")
		)
		(fp_line
			(start -1.230122 -1.599946)
			(end 2.169922 -1.599946)
			(stroke
				(width 0.1524)
				(type default)
			)
			(layer "F.SilkS")
		)
		(fp_line
			(start 2.169922 10.349992)
			(end -1.230122 10.349992)
			(stroke
				(width 0.1524)
				(type default)
			)
			(layer "F.SilkS")
		)
		(fp_line
			(start -1.230122 10.349992)
			(end -1.230122 -1.599946)
			(stroke
				(width 0.1524)
				(type default)
			)
			(layer "F.SilkS")
		)
		(fp_poly
			(pts
				(xy -2.709418 -1.590802) (xy -2.709418 -0.574802) (xy -1.439418 -1.082802)
			)
			(stroke
				(width 0)
				(type default)
			)
			(fill yes)
			(layer "F.SilkS")
		)
		(fp_poly
			(pts
				(xy -3.141218 -0.549402) (xy -3.141218 0.466598) (xy -1.871218 -0.041402)
			)
			(stroke
				(width 0)
				(type default)
			)
			(fill yes)
			(layer "B.SilkS")
		)
		(fp_poly
			(pts
				(xy -1.230122 -1.599946) (xy -1.230122 10.349992) (xy 2.169922 10.349992) (xy 2.169922 -1.599946)
			)
			(stroke
				(width 0)
				(type default)
			)
			(fill no)
			(layer "F.CrtYd")
		)
		(fp_poly
			(pts
				(xy -3.141218 -0.549402) (xy -3.141218 0.466598) (xy -1.871218 -0.041402)
			)
			(stroke
				(width 0)
				(type default)
			)
			(fill yes)
			(layer "B.Fab")
		)
		(fp_line
			(start 2.169922 -1.599946)
			(end 2.169922 10.349992)
			(stroke
				(width 0.1)
				(type default)
			)
			(layer "F.Fab")
		)
		(fp_line
			(start -1.230122 -1.599946)
			(end 2.169922 -1.599946)
			(stroke
				(width 0.1)
				(type default)
			)
			(layer "F.Fab")
		)
		(fp_line
			(start 2.169922 10.349992)
			(end -1.230122 10.349992)
			(stroke
				(width 0.1)
				(type default)
			)
			(layer "F.Fab")
		)
		(fp_line
			(start -1.230122 10.349992)
			(end -1.230122 -1.599946)
			(stroke
				(width 0.1)
				(type default)
			)
			(layer "F.Fab")
		)
		(fp_text user "8"
			(at 2.413 9.22147 90)
			(unlocked yes)
			(layer "F.SilkS")
			(effects
				(font
					(size 0.7874 0.5842)
					(thickness 0.1524)
				)
				(justify left)
			)
		)
		(fp_text user "8"
			(at -1.896618 8.83285 90)
			(unlocked yes)
			(layer "B.SilkS")
			(effects
				(font
					(size 0.7874 0.5842)
					(thickness 0.1524)
				)
				(justify left mirror)
			)
		)
		(fp_text user "8"
			(at -1.896618 8.83285 90)
			(unlocked yes)
			(layer "B.Fab")
			(effects
				(font
					(size 0.7874 0.5842)
					(thickness 0.1524)
				)
				(justify left mirror)
			)
		)
		(fp_text user "8"
			(at -2.03327 -0.381 0)
			(unlocked yes)
			(layer "F.Fab")
			(effects
				(font
					(size 0.7874 0.5842)
					(thickness 0.1524)
				)
				(justify left)
			)
		)
		(pad "1" thru_hole rect
			(at 0 0 90)
			(size 0.9906 0.9906)
			(drill 0.6096)
			(layers "*.Cu" "*.Mask")
			(remove_unused_layers no)
			(net "P3V3_STBY")
			(clearance 0.127)
			(thermal_gap 0.127)
			(padstack
				(mode front_inner_back)
				(layer "Inner"
					(shape circle)
					(size 0.9906 0.9906)
					(clearance 0.127)
				)
				(layer "B.Cu"
					(shape rect)
					(size 0.9906 0.9906)
					(clearance 0.127)
				)
			)
		)
		(pad "2" thru_hole circle
			(at 0 1.249934 90)
			(size 0.9906 0.9906)
			(drill 0.6096)
			(layers "*.Cu" "*.Mask")
			(remove_unused_layers no)
			(net "FM_MP_PS_REDUNDANT_LOST_N")
			(clearance 0.127)
			(thermal_gap 0.127)
		)
		(pad "3" thru_hole circle
			(at 0 2.500122 90)
			(size 0.9906 0.9906)
			(drill 0.6096)
			(layers "*.Cu" "*.Mask")
			(remove_unused_layers no)
			(net "FM_MP_PS_FAIL_N")
			(clearance 0.127)
			(thermal_gap 0.127)
		)
		(pad "4" thru_hole circle
			(at 0 3.750056 90)
			(size 0.9906 0.9906)
			(drill 0.6096)
			(layers "*.Cu" "*.Mask")
			(remove_unused_layers no)
			(net "FM_MATED_IN_N")
			(clearance 0.127)
			(thermal_gap 0.127)
		)
		(pad "5" thru_hole circle
			(at 0 4.99999 90)
			(size 0.9906 0.9906)
			(drill 0.6096)
			(layers "*.Cu" "*.Mask")
			(remove_unused_layers no)
			(net "IRQ_SML1_PMBUS_ALERT_R_N")
			(clearance 0.127)
			(thermal_gap 0.127)
		)
		(pad "6" thru_hole circle
			(at 0 6.249924 90)
			(size 0.9906 0.9906)
			(drill 0.6096)
			(layers "*.Cu" "*.Mask")
			(remove_unused_layers no)
			(net "SMB_BMC_PMBUS_STBY_LVC3_SDA")
			(clearance 0.127)
			(thermal_gap 0.127)
		)
		(pad "7" thru_hole circle
			(at 0 7.500112 90)
			(size 0.9906 0.9906)
			(drill 0.6096)
			(layers "*.Cu" "*.Mask")
			(remove_unused_layers no)
			(net "SMB_BMC_PMBUS_STBY_LVC3_SCL")
			(clearance 0.127)
			(thermal_gap 0.127)
		)
		(pad "8" thru_hole circle
			(at 0 8.750046 90)
			(size 0.9906 0.9906)
			(drill 0.6096)
			(layers "*.Cu" "*.Mask")
			(remove_unused_layers no)
			(net "GND")
			(clearance 0.127)
			(thermal_gap 0.127)
		)
	)
	(footprint ""
		(layer "F.Cu")
		(at 28.702 -3.766312)
		(property "Reference" "R1G15"
			(at 0 0 0)
			(layer "F.SilkS")
			(hide yes)
			(effects
				(font
					(size 1.27 1.27)
				)
			)
		)
		(property "Value" ""
			(at 0 0 0)
			(layer "F.Fab")
			(effects
				(font
					(size 1.27 1.27)
				)
			)
		)
		(duplicate_pad_numbers_are_jumpers no)
		(fp_poly
			(pts
				(xy -0.2794 -0.1016) (xy 0.2794 -0.1016) (xy 0.2794 0.9906) (xy -0.2794 0.9906)
			)
			(stroke
				(width 0)
				(type default)
			)
			(fill no)
			(layer "F.CrtYd")
		)
		(fp_line
			(start -0.2794 -0.1016)
			(end -0.2794 0.9906)
			(stroke
				(width 0.1)
				(type default)
			)
			(layer "F.Fab")
		)
		(fp_line
			(start -0.2794 0.9906)
			(end 0.2794 0.9906)
			(stroke
				(width 0.1)
				(type default)
			)
			(layer "F.Fab")
		)
		(fp_line
			(start 0.2794 -0.1016)
			(end -0.2794 -0.1016)
			(stroke
				(width 0.1)
				(type default)
			)
			(layer "F.Fab")
		)
		(fp_line
			(start 0.2794 0.9906)
			(end 0.2794 -0.1016)
			(stroke
				(width 0.1)
				(type default)
			)
			(layer "F.Fab")
		)
		(pad "1" smd rect
			(at 0 0)
			(size 0.508 0.508)
			(layers "F.Cu" "F.Mask" "F.Paste")
			(net "PVDDQ_GHJ")
		)
		(pad "2" smd rect
			(at 0 0.889)
			(size 0.508 0.508)
			(layers "F.Cu" "F.Mask" "F.Paste")
			(net "M_J_VREF")
		)
		(zone
			(layer "F.Cu")
			(hatch none 0.5)
			(connect_pads
				(clearance 0)
			)
			(min_thickness 0.25)
			(keepout
				(tracks allowed)
				(vias not_allowed)
				(pads allowed)
				(copperpour not_allowed)
				(footprints allowed)
			)
			(placement
				(enabled no)
				(sheetname "")
			)
			(fill
				(thermal_gap 0.5)
				(thermal_bridge_width 0.5)
				(island_removal_mode 0)
			)
			(polygon
				(pts
					(xy 28.448 -3.512312) (xy 28.956 -3.512312) (xy 28.956 -3.131312) (xy 28.448 -3.131312)
				)
			)
		)
		(zone
			(layer "F.Cu")
			(hatch none 0.5)
			(connect_pads
				(clearance 0)
			)
			(min_thickness 0.25)
			(keepout
				(tracks not_allowed)
				(vias allowed)
				(pads allowed)
				(copperpour not_allowed)
				(footprints allowed)
			)
			(placement
				(enabled no)
				(sheetname "")
			)
			(fill
				(thermal_gap 0.5)
				(thermal_bridge_width 0.5)
				(island_removal_mode 0)
			)
			(polygon
				(pts
					(xy 28.448 -3.131312) (xy 28.956 -3.131312) (xy 28.956 -3.512312) (xy 28.448 -3.512312)
				)
			)
		)
	)
)
